(kicad_pcb
	(version 20260206)
	(generator "pcbnew")
	(generator_version "10.0")
	(general
		(thickness 1.6)
		(legacy_teardrops no)
	)
	(paper "A4")
	(title_block
		(title "Bryce Canyon_SCC_16316-1_OCP.brd")
		(comment 1 "Bryce Canyon / footprint 64 of 1561 (U1), pads 1-120 of 1020")
	)
	(layers
		(0 "F.Cu" signal "TOP")
		(4 "In1.Cu" signal "L2GND")
		(6 "In2.Cu" signal "L3")
		(8 "In3.Cu" signal "L4VCC")
		(10 "In4.Cu" signal "L5VCC")
		(12 "In5.Cu" signal "L6")
		(14 "In6.Cu" signal "L7GND")
		(2 "B.Cu" signal "BOTTOM")
		(9 "F.Adhes" user "F.Adhesive")
		(11 "B.Adhes" user "B.Adhesive")
		(13 "F.Paste" user "Package Geometry/Pastemask Top")
		(15 "B.Paste" user "Package Geometry/Pastemask Bottom")
		(5 "F.SilkS" user "Ref Des/Silkscreen Top")
		(7 "B.SilkS" user "Ref Des/Silkscreen Bottom")
		(1 "F.Mask" user "Board Geometry/Soldermask Top")
		(3 "B.Mask" user "Board Geometry/Soldermask Bottom")
		(17 "Dwgs.User" user "User.Drawings")
		(19 "Cmts.User" user "User.Comments")
		(21 "Eco1.User" user "User.Eco1")
		(23 "Eco2.User" user "User.Eco2")
		(25 "Edge.Cuts" user "Board Geometry/Outline")
		(27 "Margin" user)
		(31 "F.CrtYd" user "Package Geometry/Place Bound Top")
		(29 "B.CrtYd" user "Package Geometry/Place Bound Bottom")
		(35 "F.Fab" user "Ref Des/Assembly Top")
		(33 "B.Fab" user "Ref Des/Assembly Bottom")
	)
	(footprint ""
		(layer "F.Cu")
		(at 115.000024 -67.00012)
		(property "Reference" "U1"
			(at 0 0 0)
			(layer "F.SilkS")
			(hide yes)
			(effects
				(font
					(size 1.27 1.27)
				)
			)
		)
		(property "Value" "LSISAS3X48-GP"
			(at -24.358092 -5.0292 0)
			(unlocked yes)
			(layer "F.Fab")
			(hide yes)
			(effects
				(font
					(size 1.016 1.016)
					(thickness 0.1524)
				)
			)
		)
		(property "Device Type" "BGA1020C33H83"
			(at -24.358092 -6.5532 0)
			(unlocked yes)
			(layer "F.Fab")
			(hide yes)
			(effects
				(font
					(size 1.016 1.016)
					(thickness 0.1524)
				)
			)
		)
		(duplicate_pad_numbers_are_jumpers no)
		(pad "A2" smd circle
			(at -14.500098 -15.500096)
			(size 0.508 0.508)
			(layers "F.Cu" "F.Mask" "F.Paste")
			(net "Net_1261")
		)
		(pad "A3" smd circle
			(at -13.5001 -15.500096)
			(size 0.508 0.508)
			(layers "F.Cu" "F.Mask" "F.Paste")
			(net "GND")
		)
		(pad "A4" smd circle
			(at -12.500102 -15.500096)
			(size 0.4572 0.4572)
			(layers "F.Cu" "F.Mask" "F.Paste")
			(net "Net_1260")
		)
		(pad "A5" smd circle
			(at -11.500104 -15.500096)
			(size 0.4572 0.4572)
			(layers "F.Cu" "F.Mask" "F.Paste")
			(net "Net_1259")
		)
		(pad "A6" smd circle
			(at -10.500106 -15.500096)
			(size 0.4572 0.4572)
			(layers "F.Cu" "F.Mask" "F.Paste")
			(net "GND")
		)
		(pad "A7" smd circle
			(at -9.500108 -15.500096)
			(size 0.4572 0.4572)
			(layers "F.Cu" "F.Mask" "F.Paste")
			(net "P1V8_E")
		)
		(pad "A8" smd circle
			(at -8.50011 -15.500096)
			(size 0.4572 0.4572)
			(layers "F.Cu" "F.Mask" "F.Paste")
			(net "GND")
		)
		(pad "A9" smd circle
			(at -7.500112 -15.500096)
			(size 0.4572 0.4572)
			(layers "F.Cu" "F.Mask" "F.Paste")
			(net "DRIVE_0_ACT")
		)
		(pad "A10" smd circle
			(at -6.500114 -15.500096)
			(size 0.4572 0.4572)
			(layers "F.Cu" "F.Mask" "F.Paste")
			(net "JTAG_EXP_TDO")
		)
		(pad "A11" smd circle
			(at -5.500116 -15.500096)
			(size 0.4572 0.4572)
			(layers "F.Cu" "F.Mask" "F.Paste")
			(net "FW_RESET_N")
		)
		(pad "A12" smd circle
			(at -4.500118 -15.500096)
			(size 0.4572 0.4572)
			(layers "F.Cu" "F.Mask" "F.Paste")
			(net "XM_WBE_0#_TP")
		)
		(pad "A13" smd circle
			(at -3.50012 -15.500096)
			(size 0.4572 0.4572)
			(layers "F.Cu" "F.Mask" "F.Paste")
			(net "XM_DATA6")
		)
		(pad "A14" smd circle
			(at -2.500122 -15.500096)
			(size 0.4572 0.4572)
			(layers "F.Cu" "F.Mask" "F.Paste")
			(net "XM_DATA3")
		)
		(pad "A15" smd circle
			(at -1.500124 -15.500096)
			(size 0.4572 0.4572)
			(layers "F.Cu" "F.Mask" "F.Paste")
			(net "XM_DATA1")
		)
		(pad "A16" smd circle
			(at -0.500126 -15.500096)
			(size 0.4572 0.4572)
			(layers "F.Cu" "F.Mask" "F.Paste")
			(net "EXP_XM_ADDR_5")
		)
		(pad "A17" smd circle
			(at 0.500126 -15.500096)
			(size 0.4572 0.4572)
			(layers "F.Cu" "F.Mask" "F.Paste")
			(net "EXP_XM_ADDR_25")
		)
		(pad "A18" smd circle
			(at 1.500124 -15.500096)
			(size 0.4572 0.4572)
			(layers "F.Cu" "F.Mask" "F.Paste")
			(net "EXP_XM_ADDR_18")
		)
		(pad "A19" smd circle
			(at 2.500122 -15.500096)
			(size 0.4572 0.4572)
			(layers "F.Cu" "F.Mask" "F.Paste")
			(net "EXP_XM_ADDR_13")
		)
		(pad "A20" smd circle
			(at 3.50012 -15.500096)
			(size 0.4572 0.4572)
			(layers "F.Cu" "F.Mask" "F.Paste")
			(net "EXP_GPIO15")
		)
		(pad "A21" smd circle
			(at 4.500118 -15.500096)
			(size 0.4572 0.4572)
			(layers "F.Cu" "F.Mask" "F.Paste")
			(net "SCC_LOC_HEARTBEAT_LS")
		)
		(pad "A22" smd circle
			(at 5.500116 -15.500096)
			(size 0.4572 0.4572)
			(layers "F.Cu" "F.Mask" "F.Paste")
			(net "BMC_EXP_SPARE_1_R_LS")
		)
		(pad "A23" smd circle
			(at 6.500114 -15.500096)
			(size 0.4572 0.4572)
			(layers "F.Cu" "F.Mask" "F.Paste")
			(net "Net_1215")
		)
		(pad "A24" smd circle
			(at 7.500112 -15.500096)
			(size 0.4572 0.4572)
			(layers "F.Cu" "F.Mask" "F.Paste")
			(net "USB_CLK")
		)
		(pad "A25" smd circle
			(at 8.50011 -15.500096)
			(size 0.4572 0.4572)
			(layers "F.Cu" "F.Mask" "F.Paste")
			(net "Net_1214")
		)
		(pad "A26" smd circle
			(at 9.500108 -15.500096)
			(size 0.4572 0.4572)
			(layers "F.Cu" "F.Mask" "F.Paste")
			(net "Net_1213")
		)
		(pad "A27" smd circle
			(at 10.500106 -15.500096)
			(size 0.4572 0.4572)
			(layers "F.Cu" "F.Mask" "F.Paste")
			(net "SDB_R_RX")
		)
		(pad "A28" smd circle
			(at 11.500104 -15.500096)
			(size 0.4572 0.4572)
			(layers "F.Cu" "F.Mask" "F.Paste")
			(net "SMART_TX")
		)
		(pad "A29" smd circle
			(at 12.500102 -15.500096)
			(size 0.4572 0.4572)
			(layers "F.Cu" "F.Mask" "F.Paste")
			(net "UART_CTS")
		)
		(pad "A30" smd circle
			(at 13.5001 -15.500096)
			(size 0.508 0.508)
			(layers "F.Cu" "F.Mask" "F.Paste")
			(net "EXP_I2C_SCL10")
		)
		(pad "A31" smd circle
			(at 14.500098 -15.500096)
			(size 0.508 0.508)
			(layers "F.Cu" "F.Mask" "F.Paste")
			(net "EXP_I2C_SCL9")
		)
		(pad "AA1" smd circle
			(at -15.500096 4.500118)
			(size 0.4572 0.4572)
			(layers "F.Cu" "F.Mask" "F.Paste")
			(net "DRIVE_19_ACT")
		)
		(pad "AA2" smd circle
			(at -14.500098 4.500118)
			(size 0.4572 0.4572)
			(layers "F.Cu" "F.Mask" "F.Paste")
			(net "DRIVE_20_ACT")
		)
		(pad "AA3" smd circle
			(at -13.5001 4.500118)
			(size 0.4572 0.4572)
			(layers "F.Cu" "F.Mask" "F.Paste")
			(net "P1V8_E")
		)
		(pad "AA4" smd circle
			(at -12.500102 4.500118)
			(size 0.4572 0.4572)
			(layers "F.Cu" "F.Mask" "F.Paste")
			(net "DRIVE_23_ACT")
		)
		(pad "AA5" smd circle
			(at -11.500104 4.500118)
			(size 0.4572 0.4572)
			(layers "F.Cu" "F.Mask" "F.Paste")
			(net "DRIVE_22_ACT")
		)
		(pad "AA6" smd circle
			(at -10.500106 4.500118)
			(size 0.4572 0.4572)
			(layers "F.Cu" "F.Mask" "F.Paste")
			(net "GND")
		)
		(pad "AA7" smd circle
			(at -9.500108 4.500118)
			(size 0.4572 0.4572)
			(layers "F.Cu" "F.Mask" "F.Paste")
			(net "DRIVE_24_ACT")
		)
		(pad "AA8" smd circle
			(at -8.50011 4.500118)
			(size 0.4572 0.4572)
			(layers "F.Cu" "F.Mask" "F.Paste")
			(net "DRIVE_36_ACT")
		)
		(pad "AA9" smd circle
			(at -7.500112 4.500118)
			(size 0.4572 0.4572)
			(layers "F.Cu" "F.Mask" "F.Paste")
			(net "LED46")
		)
		(pad "AA10" smd circle
			(at -6.500114 4.500118)
			(size 0.4572 0.4572)
			(layers "F.Cu" "F.Mask" "F.Paste")
			(net "GND")
		)
		(pad "AA11" smd circle
			(at -5.500116 4.500118)
			(size 0.4572 0.4572)
			(layers "F.Cu" "F.Mask" "F.Paste")
			(net "GB_VDDH")
		)
		(pad "AA12" smd circle
			(at -4.500118 4.500118)
			(size 0.4572 0.4572)
			(layers "F.Cu" "F.Mask" "F.Paste")
			(net "GB_VDDH")
		)
		(pad "AA13" smd circle
			(at -3.50012 4.500118)
			(size 0.4572 0.4572)
			(layers "F.Cu" "F.Mask" "F.Paste")
			(net "GB_VDDH")
		)
		(pad "AA14" smd circle
			(at -2.500122 4.500118)
			(size 0.4572 0.4572)
			(layers "F.Cu" "F.Mask" "F.Paste")
			(net "GB_VDDH")
		)
		(pad "AA15" smd circle
			(at -1.500124 4.500118)
			(size 0.4572 0.4572)
			(layers "F.Cu" "F.Mask" "F.Paste")
			(net "GB_VDDH")
		)
		(pad "AA16" smd circle
			(at -0.500126 4.500118)
			(size 0.4572 0.4572)
			(layers "F.Cu" "F.Mask" "F.Paste")
			(net "GB_VDDH")
		)
		(pad "AA17" smd circle
			(at 0.500126 4.500118)
			(size 0.4572 0.4572)
			(layers "F.Cu" "F.Mask" "F.Paste")
			(net "GB_VDDH")
		)
		(pad "AA18" smd circle
			(at 1.500124 4.500118)
			(size 0.4572 0.4572)
			(layers "F.Cu" "F.Mask" "F.Paste")
			(net "GB_VDDH")
		)
		(pad "AA19" smd circle
			(at 2.500122 4.500118)
			(size 0.4572 0.4572)
			(layers "F.Cu" "F.Mask" "F.Paste")
			(net "GB_VDDH")
		)
		(pad "AA20" smd circle
			(at 3.50012 4.500118)
			(size 0.4572 0.4572)
			(layers "F.Cu" "F.Mask" "F.Paste")
			(net "GB_VDDH")
		)
		(pad "AA21" smd circle
			(at 4.500118 4.500118)
			(size 0.4572 0.4572)
			(layers "F.Cu" "F.Mask" "F.Paste")
			(net "GB_VDDH")
		)
		(pad "AA22" smd circle
			(at 5.500116 4.500118)
			(size 0.4572 0.4572)
			(layers "F.Cu" "F.Mask" "F.Paste")
			(net "GB_VDDH")
		)
		(pad "AA23" smd circle
			(at 6.500114 4.500118)
			(size 0.4572 0.4572)
			(layers "F.Cu" "F.Mask" "F.Paste")
			(net "GND")
		)
		(pad "AA24" smd circle
			(at 7.500112 4.500118)
			(size 0.4572 0.4572)
			(layers "F.Cu" "F.Mask" "F.Paste")
			(net "GB_VDDA")
		)
		(pad "AA25" smd circle
			(at 8.50011 4.500118)
			(size 0.4572 0.4572)
			(layers "F.Cu" "F.Mask" "F.Paste")
			(net "GND")
		)
		(pad "AA26" smd circle
			(at 9.500108 4.500118)
			(size 0.4572 0.4572)
			(layers "F.Cu" "F.Mask" "F.Paste")
			(net "GB_VDDA")
		)
		(pad "AA27" smd circle
			(at 10.500106 4.500118)
			(size 0.4572 0.4572)
			(layers "F.Cu" "F.Mask" "F.Paste")
			(net "PHY_DPB_TO_SCC_C_29_DN")
		)
		(pad "AA28" smd circle
			(at 11.500104 4.500118)
			(size 0.4572 0.4572)
			(layers "F.Cu" "F.Mask" "F.Paste")
			(net "PHY_DPB_TO_SCC_C_29_DP")
		)
		(pad "AA29" smd circle
			(at 12.500102 4.500118)
			(size 0.4572 0.4572)
			(layers "F.Cu" "F.Mask" "F.Paste")
			(net "GND")
		)
		(pad "AA30" smd circle
			(at 13.5001 4.500118)
			(size 0.4572 0.4572)
			(layers "F.Cu" "F.Mask" "F.Paste")
			(net "GB_VDDA")
		)
		(pad "AA31" smd circle
			(at 14.500098 4.500118)
			(size 0.4572 0.4572)
			(layers "F.Cu" "F.Mask" "F.Paste")
			(net "PHY_SCC_TO_DPB_29_DN")
		)
		(pad "AA32" smd circle
			(at 15.500096 4.500118)
			(size 0.4572 0.4572)
			(layers "F.Cu" "F.Mask" "F.Paste")
			(net "PHY_SCC_TO_DPB_29_DP")
		)
		(pad "AB1" smd circle
			(at -15.500096 5.500116)
			(size 0.4572 0.4572)
			(layers "F.Cu" "F.Mask" "F.Paste")
			(net "DRIVE_25_ACT")
		)
		(pad "AB2" smd circle
			(at -14.500098 5.500116)
			(size 0.4572 0.4572)
			(layers "F.Cu" "F.Mask" "F.Paste")
			(net "DRIVE_28_ACT")
		)
		(pad "AB3" smd circle
			(at -13.5001 5.500116)
			(size 0.4572 0.4572)
			(layers "F.Cu" "F.Mask" "F.Paste")
			(net "GND")
		)
		(pad "AB4" smd circle
			(at -12.500102 5.500116)
			(size 0.4572 0.4572)
			(layers "F.Cu" "F.Mask" "F.Paste")
			(net "DRIVE_27_ACT")
		)
		(pad "AB5" smd circle
			(at -11.500104 5.500116)
			(size 0.4572 0.4572)
			(layers "F.Cu" "F.Mask" "F.Paste")
			(net "DRIVE_29_ACT")
		)
		(pad "AB6" smd circle
			(at -10.500106 5.500116)
			(size 0.4572 0.4572)
			(layers "F.Cu" "F.Mask" "F.Paste")
			(net "P1V8_E")
		)
		(pad "AB7" smd circle
			(at -9.500108 5.500116)
			(size 0.4572 0.4572)
			(layers "F.Cu" "F.Mask" "F.Paste")
			(net "DRIVE_30_ACT")
		)
		(pad "AB8" smd circle
			(at -8.50011 5.500116)
			(size 0.4572 0.4572)
			(layers "F.Cu" "F.Mask" "F.Paste")
			(net "LED41")
		)
		(pad "AB9" smd circle
			(at -7.500112 5.500116)
			(size 0.4572 0.4572)
			(layers "F.Cu" "F.Mask" "F.Paste")
			(net "P1V8_E")
		)
		(pad "AB10" smd circle
			(at -6.500114 5.500116)
			(size 0.4572 0.4572)
			(layers "F.Cu" "F.Mask" "F.Paste")
			(net "GND")
		)
		(pad "AB11" smd circle
			(at -5.500116 5.500116)
			(size 0.4572 0.4572)
			(layers "F.Cu" "F.Mask" "F.Paste")
			(net "GND")
		)
		(pad "AB12" smd circle
			(at -4.500118 5.500116)
			(size 0.4572 0.4572)
			(layers "F.Cu" "F.Mask" "F.Paste")
			(net "GND")
		)
		(pad "AB13" smd circle
			(at -3.50012 5.500116)
			(size 0.4572 0.4572)
			(layers "F.Cu" "F.Mask" "F.Paste")
			(net "GND")
		)
		(pad "AB14" smd circle
			(at -2.500122 5.500116)
			(size 0.4572 0.4572)
			(layers "F.Cu" "F.Mask" "F.Paste")
			(net "GND")
		)
		(pad "AB15" smd circle
			(at -1.500124 5.500116)
			(size 0.4572 0.4572)
			(layers "F.Cu" "F.Mask" "F.Paste")
			(net "GND")
		)
		(pad "AB16" smd circle
			(at -0.500126 5.500116)
			(size 0.4572 0.4572)
			(layers "F.Cu" "F.Mask" "F.Paste")
			(net "GND")
		)
		(pad "AB17" smd circle
			(at 0.500126 5.500116)
			(size 0.4572 0.4572)
			(layers "F.Cu" "F.Mask" "F.Paste")
			(net "GND")
		)
		(pad "AB18" smd circle
			(at 1.500124 5.500116)
			(size 0.4572 0.4572)
			(layers "F.Cu" "F.Mask" "F.Paste")
			(net "GND")
		)
		(pad "AB19" smd circle
			(at 2.500122 5.500116)
			(size 0.4572 0.4572)
			(layers "F.Cu" "F.Mask" "F.Paste")
			(net "GND")
		)
		(pad "AB20" smd circle
			(at 3.50012 5.500116)
			(size 0.4572 0.4572)
			(layers "F.Cu" "F.Mask" "F.Paste")
			(net "GND")
		)
		(pad "AB21" smd circle
			(at 4.500118 5.500116)
			(size 0.4572 0.4572)
			(layers "F.Cu" "F.Mask" "F.Paste")
			(net "GND")
		)
		(pad "AB22" smd circle
			(at 5.500116 5.500116)
			(size 0.4572 0.4572)
			(layers "F.Cu" "F.Mask" "F.Paste")
			(net "GND")
		)
		(pad "AB23" smd circle
			(at 6.500114 5.500116)
			(size 0.4572 0.4572)
			(layers "F.Cu" "F.Mask" "F.Paste")
			(net "GND")
		)
		(pad "AB24" smd circle
			(at 7.500112 5.500116)
			(size 0.4572 0.4572)
			(layers "F.Cu" "F.Mask" "F.Paste")
			(net "GND")
		)
		(pad "AB25" smd circle
			(at 8.50011 5.500116)
			(size 0.4572 0.4572)
			(layers "F.Cu" "F.Mask" "F.Paste")
			(net "GND")
		)
		(pad "AB26" smd circle
			(at 9.500108 5.500116)
			(size 0.4572 0.4572)
			(layers "F.Cu" "F.Mask" "F.Paste")
			(net "GND")
		)
		(pad "AB27" smd circle
			(at 10.500106 5.500116)
			(size 0.4572 0.4572)
			(layers "F.Cu" "F.Mask" "F.Paste")
			(net "PHY_DPB_TO_SCC_C_28_DN")
		)
		(pad "AB28" smd circle
			(at 11.500104 5.500116)
			(size 0.4572 0.4572)
			(layers "F.Cu" "F.Mask" "F.Paste")
			(net "PHY_DPB_TO_SCC_C_28_DP")
		)
		(pad "AB29" smd circle
			(at 12.500102 5.500116)
			(size 0.4572 0.4572)
			(layers "F.Cu" "F.Mask" "F.Paste")
			(net "GB_VDDA")
		)
		(pad "AB30" smd circle
			(at 13.5001 5.500116)
			(size 0.4572 0.4572)
			(layers "F.Cu" "F.Mask" "F.Paste")
			(net "PHY_SCC_TO_DPB_28_DN")
		)
		(pad "AB31" smd circle
			(at 14.500098 5.500116)
			(size 0.4572 0.4572)
			(layers "F.Cu" "F.Mask" "F.Paste")
			(net "PHY_SCC_TO_DPB_28_DP")
		)
		(pad "AB32" smd circle
			(at 15.500096 5.500116)
			(size 0.4572 0.4572)
			(layers "F.Cu" "F.Mask" "F.Paste")
			(net "GND")
		)
		(pad "AC1" smd circle
			(at -15.500096 6.500114)
			(size 0.4572 0.4572)
			(layers "F.Cu" "F.Mask" "F.Paste")
			(net "DRIVE_33_ACT")
		)
		(pad "AC2" smd circle
			(at -14.500098 6.500114)
			(size 0.4572 0.4572)
			(layers "F.Cu" "F.Mask" "F.Paste")
			(net "DRIVE_32_ACT")
		)
		(pad "AC3" smd circle
			(at -13.5001 6.500114)
			(size 0.4572 0.4572)
			(layers "F.Cu" "F.Mask" "F.Paste")
			(net "P1V8_E")
		)
		(pad "AC4" smd circle
			(at -12.500102 6.500114)
			(size 0.4572 0.4572)
			(layers "F.Cu" "F.Mask" "F.Paste")
			(net "DRIVE_34_ACT")
		)
		(pad "AC5" smd circle
			(at -11.500104 6.500114)
			(size 0.4572 0.4572)
			(layers "F.Cu" "F.Mask" "F.Paste")
			(net "DRIVE_35_ACT")
		)
		(pad "AC6" smd circle
			(at -10.500106 6.500114)
			(size 0.4572 0.4572)
			(layers "F.Cu" "F.Mask" "F.Paste")
			(net "GND")
		)
		(pad "AC7" smd circle
			(at -9.500108 6.500114)
			(size 0.4572 0.4572)
			(layers "F.Cu" "F.Mask" "F.Paste")
			(net "DRIVE_38_ACT")
		)
		(pad "AC8" smd circle
			(at -8.50011 6.500114)
			(size 0.4572 0.4572)
			(layers "F.Cu" "F.Mask" "F.Paste")
			(net "LED47")
		)
		(pad "AC9" smd circle
			(at -7.500112 6.500114)
			(size 0.4572 0.4572)
			(layers "F.Cu" "F.Mask" "F.Paste")
			(net "GND")
		)
		(pad "AC10" smd circle
			(at -6.500114 6.500114)
			(size 0.4572 0.4572)
			(layers "F.Cu" "F.Mask" "F.Paste")
			(net "GND")
		)
		(pad "AC11" smd circle
			(at -5.500116 6.500114)
			(size 0.4572 0.4572)
			(layers "F.Cu" "F.Mask" "F.Paste")
			(net "GB_VDDA")
		)
		(pad "AC12" smd circle
			(at -4.500118 6.500114)
			(size 0.4572 0.4572)
			(layers "F.Cu" "F.Mask" "F.Paste")
			(net "GND")
		)
		(pad "AC13" smd circle
			(at -3.50012 6.500114)
			(size 0.4572 0.4572)
			(layers "F.Cu" "F.Mask" "F.Paste")
			(net "GB_VDDA")
		)
		(pad "AC14" smd circle
			(at -2.500122 6.500114)
			(size 0.4572 0.4572)
			(layers "F.Cu" "F.Mask" "F.Paste")
			(net "GND")
		)
		(pad "AC15" smd circle
			(at -1.500124 6.500114)
			(size 0.4572 0.4572)
			(layers "F.Cu" "F.Mask" "F.Paste")
			(net "GB_VDDA")
		)
		(pad "AC16" smd circle
			(at -0.500126 6.500114)
			(size 0.4572 0.4572)
			(layers "F.Cu" "F.Mask" "F.Paste")
			(net "GND")
		)
		(pad "AC17" smd circle
			(at 0.500126 6.500114)
			(size 0.4572 0.4572)
			(layers "F.Cu" "F.Mask" "F.Paste")
			(net "GB_VDDA")
		)
		(pad "AC18" smd circle
			(at 1.500124 6.500114)
			(size 0.4572 0.4572)
			(layers "F.Cu" "F.Mask" "F.Paste")
			(net "GND")
		)
		(pad "AC19" smd circle
			(at 2.500122 6.500114)
			(size 0.4572 0.4572)
			(layers "F.Cu" "F.Mask" "F.Paste")
			(net "GB_VDDA")
		)
		(pad "AC20" smd circle
			(at 3.50012 6.500114)
			(size 0.4572 0.4572)
			(layers "F.Cu" "F.Mask" "F.Paste")
			(net "GND")
		)
		(pad "AC21" smd circle
			(at 4.500118 6.500114)
			(size 0.4572 0.4572)
			(layers "F.Cu" "F.Mask" "F.Paste")
			(net "GB_VDDA")
		)
		(pad "AC22" smd circle
			(at 5.500116 6.500114)
			(size 0.4572 0.4572)
			(layers "F.Cu" "F.Mask" "F.Paste")
			(net "GND")
		)
		(pad "AC23" smd circle
			(at 6.500114 6.500114)
			(size 0.4572 0.4572)
			(layers "F.Cu" "F.Mask" "F.Paste")
			(net "GND")
		)
		(pad "AC24" smd circle
			(at 7.500112 6.500114)
			(size 0.4572 0.4572)
			(layers "F.Cu" "F.Mask" "F.Paste")
			(net "GB_VDDA")
		)
		(pad "AC25" smd circle
			(at 8.50011 6.500114)
			(size 0.4572 0.4572)
			(layers "F.Cu" "F.Mask" "F.Paste")
			(net "GND")
		)
		(pad "AC26" smd circle
			(at 9.500108 6.500114)
			(size 0.4572 0.4572)
			(layers "F.Cu" "F.Mask" "F.Paste")
			(net "GND")
		)
	)
)
